(kicad_pcb
	(version 20241229)
	(generator "pcbnew")
	(generator_version "9.0")
	(general
		(thickness 0.761)
		(legacy_teardrops no)
	)
	(paper "A4")
	(title_block
		(title " M.2 to OCuLink adapter")
		(date "2025-07-16")
		(rev "1.0.2")
		(company "Antmicro Ltd")
		(comment 1 "www.antmicro.com")
		(comment 9 "footprints 18-22 of 22")
	)
	(layers
		(0 "F.Cu" signal)
		(4 "In1.Cu" signal)
		(6 "In2.Cu" signal)
		(2 "B.Cu" signal)
		(9 "F.Adhes" user "F.Adhesive")
		(11 "B.Adhes" user "B.Adhesive")
		(13 "F.Paste" user)
		(15 "B.Paste" user)
		(5 "F.SilkS" user "F.Silkscreen")
		(7 "B.SilkS" user "B.Silkscreen")
		(1 "F.Mask" user)
		(3 "B.Mask" user)
		(17 "Dwgs.User" user "User.Drawings")
		(19 "Cmts.User" user "User.Comments")
		(21 "Eco1.User" user "User.Eco1")
		(23 "Eco2.User" user "User.Eco2")
		(25 "Edge.Cuts" user)
		(27 "Margin" user)
		(31 "F.CrtYd" user "F.Courtyard")
		(29 "B.CrtYd" user "B.Courtyard")
		(35 "F.Fab" user)
		(33 "B.Fab" user)
	)
	(footprint "antmicro-footprints:R_0402_1005Metric"
		(layer "B.Cu")
		(at 151.83 90.09 180)
		(descr "Resistor SMD 0402")
		(tags "resistor SMD 0402")
		(property "Reference" "R8"
			(at -2.45 -0.41 0)
			(layer "B.SilkS")
			(effects
				(font
					(size 0.7 0.7)
					(thickness 0.15)
				)
				(justify left bottom mirror)
			)
		)
		(property "Value" "R_0R_0402"
			(at -1.011843 -1.772047 0)
			(layer "B.Fab")
			(effects
				(font
					(size 0.7 0.7)
					(thickness 0.15)
				)
				(justify left bottom mirror)
			)
		)
		(property "Datasheet" "https://industrial.panasonic.com/cdbs/www-data/pdf/RDA0000/AOA0000C301.pdf"
			(at 0 0 0)
			(layer "B.Fab")
			(hide yes)
			(effects
				(font
					(size 1.27 1.27)
					(thickness 0.15)
				)
				(justify mirror)
			)
		)
		(property "Description" "SMD Chip Resistor, Jumper, 0 ohm, 100 mW, 0402 [1005 Metric], Thick Film, General Purpose"
			(at 0 0 0)
			(layer "B.Fab")
			(hide yes)
			(effects
				(font
					(size 1.27 1.27)
					(thickness 0.15)
				)
				(justify mirror)
			)
		)
		(property "MPN" "ERJ2GE0R00X"
			(at 0 0 0)
			(unlocked yes)
			(layer "B.Fab")
			(hide yes)
			(effects
				(font
					(size 1 1)
					(thickness 0.15)
				)
				(justify mirror)
			)
		)
		(property "Manufacturer" "Panasonic"
			(at 0 0 0)
			(unlocked yes)
			(layer "B.Fab")
			(hide yes)
			(effects
				(font
					(size 1 1)
					(thickness 0.15)
				)
				(justify mirror)
			)
		)
		(property "License" "Apache-2.0"
			(at 0 0 0)
			(unlocked yes)
			(layer "B.Fab")
			(hide yes)
			(effects
				(font
					(size 1 1)
					(thickness 0.15)
				)
				(justify mirror)
			)
		)
		(property "Author" "Antmicro"
			(at 0 0 0)
			(unlocked yes)
			(layer "B.Fab")
			(hide yes)
			(effects
				(font
					(size 1 1)
					(thickness 0.15)
				)
				(justify mirror)
			)
		)
		(property "Val" "0R"
			(at 0 0 0)
			(unlocked yes)
			(layer "B.Fab")
			(hide yes)
			(effects
				(font
					(size 1 1)
					(thickness 0.15)
				)
				(justify mirror)
			)
		)
		(property "Tolerance" ""
			(at 0 0 0)
			(unlocked yes)
			(layer "B.Fab")
			(hide yes)
			(effects
				(font
					(size 1 1)
					(thickness 0.15)
				)
				(justify mirror)
			)
		)
		(property "Current" "1A"
			(at 0 0 0)
			(unlocked yes)
			(layer "B.Fab")
			(hide yes)
			(effects
				(font
					(size 1 1)
					(thickness 0.15)
				)
				(justify mirror)
			)
		)
		(sheetname "/")
		(sheetfile "antmicro-m2-oculink-adapter-hw.kicad_sch")
		(attr smd)
		(fp_rect
			(start -0.925 0.47)
			(end 0.925 -0.47)
			(stroke
				(width 0.05)
				(type default)
			)
			(fill no)
			(layer "B.CrtYd")
		)
		(fp_rect
			(start -0.5 0.25)
			(end 0.5 -0.25)
			(stroke
				(width 0.15)
				(type solid)
			)
			(fill no)
			(layer "B.Fab")
		)
		(fp_text user "${REFERENCE}"
			(at -0.95 -3.168 0)
			(layer "B.Fab")
			(effects
				(font
					(size 0.7 0.7)
					(thickness 0.15)
				)
				(justify left bottom mirror)
			)
		)
		(fp_text user "Author: Antmicro"
			(at -0.95 -4.169 0)
			(layer "B.Fab")
			(effects
				(font
					(size 0.7 0.7)
					(thickness 0.15)
				)
				(justify left bottom mirror)
			)
		)
		(fp_text user "License: Apache-2.0"
			(at -0.95 -5.169 0)
			(layer "B.Fab")
			(effects
				(font
					(size 0.7 0.7)
					(thickness 0.15)
				)
				(justify left bottom mirror)
			)
		)
		(pad "1" smd roundrect
			(at -0.48 0 180)
			(size 0.59 0.64)
			(layers "B.Cu" "B.Mask" "B.Paste")
			(roundrect_rratio 0.25)
			(net 56 "Net-(C1-Pad2)")
			(pintype "passive")
		)
		(pad "2" smd roundrect
			(at 0.48 0 180)
			(size 0.59 0.64)
			(layers "B.Cu" "B.Mask" "B.Paste")
			(roundrect_rratio 0.25)
			(net 17 "+3V3")
			(pintype "passive")
		)
	)
	(footprint "antmicro-footprints:C_0402_1005Metric"
		(layer "B.Cu")
		(at 151.47 95.09 90)
		(descr "Capacitor SMD 0402")
		(tags "capacitor SMD 0402")
		(property "Reference" "C4"
			(at 0.91 -0.33 90)
			(layer "B.SilkS")
			(effects
				(font
					(size 0.7 0.7)
					(thickness 0.15)
				)
				(justify right top mirror)
			)
		)
		(property "Value" "C_100n_16V_X7R_0402"
			(at -1.022927 -2.155213 90)
			(layer "B.Fab")
			(effects
				(font
					(size 0.7 0.7)
					(thickness 0.15)
				)
				(justify right top mirror)
			)
		)
		(property "Datasheet" "https://www.kemet.com/en/us/capacitors/product/C0402C104J4RAC7411.html"
			(at 0 0 90)
			(layer "B.Fab")
			(hide yes)
			(effects
				(font
					(size 1.27 1.27)
					(thickness 0.15)
				)
				(justify mirror)
			)
		)
		(property "Description" "SMD Multilayer Ceramic Capacitor, 100nF, 50V, 0402, ±5%, X7R"
			(at 0 0 90)
			(layer "B.Fab")
			(hide yes)
			(effects
				(font
					(size 1.27 1.27)
					(thickness 0.15)
				)
				(justify mirror)
			)
		)
		(property "MPN" "C0402C104J4RAC7411"
			(at 0 0 270)
			(unlocked yes)
			(layer "B.Fab")
			(hide yes)
			(effects
				(font
					(size 1 1)
					(thickness 0.15)
				)
				(justify mirror)
			)
		)
		(property "Val" "100n"
			(at 0 0 270)
			(unlocked yes)
			(layer "B.Fab")
			(hide yes)
			(effects
				(font
					(size 1 1)
					(thickness 0.15)
				)
				(justify mirror)
			)
		)
		(property "Voltage" "16V"
			(at 0 0 270)
			(unlocked yes)
			(layer "B.Fab")
			(hide yes)
			(effects
				(font
					(size 1 1)
					(thickness 0.15)
				)
				(justify mirror)
			)
		)
		(property "Dielectric" "X7R"
			(at 0 0 270)
			(unlocked yes)
			(layer "B.Fab")
			(hide yes)
			(effects
				(font
					(size 1 1)
					(thickness 0.15)
				)
				(justify mirror)
			)
		)
		(property "Manufacturer" "KEMET"
			(at 0 0 270)
			(unlocked yes)
			(layer "B.Fab")
			(hide yes)
			(effects
				(font
					(size 1 1)
					(thickness 0.15)
				)
				(justify mirror)
			)
		)
		(property "License" "Apache-2.0"
			(at 0 0 270)
			(unlocked yes)
			(layer "B.Fab")
			(hide yes)
			(effects
				(font
					(size 1 1)
					(thickness 0.15)
				)
				(justify mirror)
			)
		)
		(property "Author" "Antmicro"
			(at 0 0 270)
			(unlocked yes)
			(layer "B.Fab")
			(hide yes)
			(effects
				(font
					(size 1 1)
					(thickness 0.15)
				)
				(justify mirror)
			)
		)
		(sheetname "/")
		(sheetfile "antmicro-m2-oculink-adapter-hw.kicad_sch")
		(attr smd)
		(fp_rect
			(start -0.925 0.47)
			(end 0.925 -0.47)
			(stroke
				(width 0.05)
				(type default)
			)
			(fill no)
			(layer "B.CrtYd")
		)
		(fp_line
			(start 0.504 -0.248)
			(end -0.494 -0.248)
			(stroke
				(width 0.15)
				(type solid)
			)
			(layer "B.Fab")
		)
		(fp_line
			(start -0.494 -0.248)
			(end -0.494 0.25)
			(stroke
				(width 0.15)
				(type solid)
			)
			(layer "B.Fab")
		)
		(fp_line
			(start 0.504 0.25)
			(end 0.504 -0.248)
			(stroke
				(width 0.15)
				(type solid)
			)
			(layer "B.Fab")
		)
		(fp_line
			(start -0.494 0.25)
			(end 0.504 0.25)
			(stroke
				(width 0.15)
				(type solid)
			)
			(layer "B.Fab")
		)
		(fp_text user "${REFERENCE}"
			(at -0.939 -4.599 90)
			(layer "B.Fab")
			(effects
				(font
					(size 0.7 0.7)
					(thickness 0.15)
				)
				(justify right top mirror)
			)
		)
		(fp_text user "License: Apache-2.0"
			(at -0.939 -5.799 90)
			(layer "B.Fab")
			(effects
				(font
					(size 0.7 0.7)
					(thickness 0.15)
				)
				(justify right top mirror)
			)
		)
		(fp_text user "Author: Antmicro"
			(at -0.939 -3.399 90)
			(layer "B.Fab")
			(effects
				(font
					(size 0.7 0.7)
					(thickness 0.15)
				)
				(justify right top mirror)
			)
		)
		(pad "1" smd roundrect
			(at -0.48 0 90)
			(size 0.59 0.64)
			(layers "B.Cu" "B.Mask" "B.Paste")
			(roundrect_rratio 0.25)
			(net 1 "GND")
			(pintype "passive")
		)
		(pad "2" smd roundrect
			(at 0.48 0 90)
			(size 0.59 0.64)
			(layers "B.Cu" "B.Mask" "B.Paste")
			(roundrect_rratio 0.25)
			(net 57 "Net-(J2-V_{ACT}_TX_3V3)")
			(pintype "passive")
		)
	)
	(footprint "antmicro-footprints:C_0402_1005Metric"
		(layer "B.Cu")
		(at 156.29 124.22 90)
		(descr "Capacitor SMD 0402")
		(tags "capacitor SMD 0402")
		(property "Reference" "C1"
			(at 1.37 -0.33 90)
			(layer "B.SilkS")
			(effects
				(font
					(size 0.7 0.7)
					(thickness 0.15)
				)
				(justify right top mirror)
			)
		)
		(property "Value" "C_100n_16V_X7R_0402"
			(at -1.022927 -2.155213 90)
			(layer "B.Fab")
			(effects
				(font
					(size 0.7 0.7)
					(thickness 0.15)
				)
				(justify right top mirror)
			)
		)
		(property "Datasheet" "https://www.kemet.com/en/us/capacitors/product/C0402C104J4RAC7411.html"
			(at 0 0 90)
			(layer "B.Fab")
			(hide yes)
			(effects
				(font
					(size 1.27 1.27)
					(thickness 0.15)
				)
				(justify mirror)
			)
		)
		(property "Description" "SMD Multilayer Ceramic Capacitor, 100nF, 50V, 0402, ±5%, X7R"
			(at 0 0 90)
			(layer "B.Fab")
			(hide yes)
			(effects
				(font
					(size 1.27 1.27)
					(thickness 0.15)
				)
				(justify mirror)
			)
		)
		(property "MPN" "C0402C104J4RAC7411"
			(at 0 0 270)
			(unlocked yes)
			(layer "B.Fab")
			(hide yes)
			(effects
				(font
					(size 1 1)
					(thickness 0.15)
				)
				(justify mirror)
			)
		)
		(property "Val" "100n"
			(at 0 0 270)
			(unlocked yes)
			(layer "B.Fab")
			(hide yes)
			(effects
				(font
					(size 1 1)
					(thickness 0.15)
				)
				(justify mirror)
			)
		)
		(property "Voltage" "16V"
			(at 0 0 270)
			(unlocked yes)
			(layer "B.Fab")
			(hide yes)
			(effects
				(font
					(size 1 1)
					(thickness 0.15)
				)
				(justify mirror)
			)
		)
		(property "Dielectric" "X7R"
			(at 0 0 270)
			(unlocked yes)
			(layer "B.Fab")
			(hide yes)
			(effects
				(font
					(size 1 1)
					(thickness 0.15)
				)
				(justify mirror)
			)
		)
		(property "Manufacturer" "KEMET"
			(at 0 0 270)
			(unlocked yes)
			(layer "B.Fab")
			(hide yes)
			(effects
				(font
					(size 1 1)
					(thickness 0.15)
				)
				(justify mirror)
			)
		)
		(property "License" "Apache-2.0"
			(at 0 0 270)
			(unlocked yes)
			(layer "B.Fab")
			(hide yes)
			(effects
				(font
					(size 1 1)
					(thickness 0.15)
				)
				(justify mirror)
			)
		)
		(property "Author" "Antmicro"
			(at 0 0 270)
			(unlocked yes)
			(layer "B.Fab")
			(hide yes)
			(effects
				(font
					(size 1 1)
					(thickness 0.15)
				)
				(justify mirror)
			)
		)
		(sheetname "/")
		(sheetfile "antmicro-m2-oculink-adapter-hw.kicad_sch")
		(attr smd)
		(fp_rect
			(start -0.925 0.47)
			(end 0.925 -0.47)
			(stroke
				(width 0.05)
				(type default)
			)
			(fill no)
			(layer "B.CrtYd")
		)
		(fp_line
			(start 0.504 -0.248)
			(end -0.494 -0.248)
			(stroke
				(width 0.15)
				(type solid)
			)
			(layer "B.Fab")
		)
		(fp_line
			(start -0.494 -0.248)
			(end -0.494 0.25)
			(stroke
				(width 0.15)
				(type solid)
			)
			(layer "B.Fab")
		)
		(fp_line
			(start 0.504 0.25)
			(end 0.504 -0.248)
			(stroke
				(width 0.15)
				(type solid)
			)
			(layer "B.Fab")
		)
		(fp_line
			(start -0.494 0.25)
			(end 0.504 0.25)
			(stroke
				(width 0.15)
				(type solid)
			)
			(layer "B.Fab")
		)
		(fp_text user "License: Apache-2.0"
			(at -0.939 -5.799 90)
			(layer "B.Fab")
			(effects
				(font
					(size 0.7 0.7)
					(thickness 0.15)
				)
				(justify right top mirror)
			)
		)
		(fp_text user "Author: Antmicro"
			(at -0.939 -3.399 90)
			(layer "B.Fab")
			(effects
				(font
					(size 0.7 0.7)
					(thickness 0.15)
				)
				(justify right top mirror)
			)
		)
		(fp_text user "${REFERENCE}"
			(at -0.939 -4.599 90)
			(layer "B.Fab")
			(effects
				(font
					(size 0.7 0.7)
					(thickness 0.15)
				)
				(justify right top mirror)
			)
		)
		(pad "1" smd roundrect
			(at -0.48 0 90)
			(size 0.59 0.64)
			(layers "B.Cu" "B.Mask" "B.Paste")
			(roundrect_rratio 0.25)
			(net 1 "GND")
			(pintype "passive")
		)
		(pad "2" smd roundrect
			(at 0.48 0 90)
			(size 0.59 0.64)
			(layers "B.Cu" "B.Mask" "B.Paste")
			(roundrect_rratio 0.25)
			(net 56 "Net-(C1-Pad2)")
			(pintype "passive")
		)
	)
	(footprint "antmicro-footprints:R_0201"
		(layer "B.Cu")
		(at 145.61 95.34 180)
		(descr "Resistor SMD 0201")
		(tags "resistor SMD 0201")
		(property "Reference" "R2"
			(at 0.58 -3.068916 0)
			(layer "B.SilkS")
			(effects
				(font
					(size 0.7 0.7)
					(thickness 0.15)
				)
				(justify left bottom mirror)
			)
		)
		(property "Value" "R_0R_0201"
			(at 0 -1.25 0)
			(layer "B.Fab")
			(effects
				(font
					(size 0.7 0.7)
					(thickness 0.15)
				)
				(justify left bottom mirror)
			)
		)
		(property "Datasheet" "https://www.bourns.com/docs/product-datasheets/cr.pdf"
			(at 0 0 0)
			(layer "B.Fab")
			(hide yes)
			(effects
				(font
					(size 1.27 1.27)
					(thickness 0.15)
				)
				(justify mirror)
			)
		)
		(property "Description" "SMD Chip Resistor"
			(at 0 0 0)
			(layer "B.Fab")
			(hide yes)
			(effects
				(font
					(size 1.27 1.27)
					(thickness 0.15)
				)
				(justify mirror)
			)
		)
		(property "MPN" "CR0201-FX-0R00GLF"
			(at 0 0 0)
			(unlocked yes)
			(layer "B.Fab")
			(hide yes)
			(effects
				(font
					(size 1 1)
					(thickness 0.15)
				)
				(justify mirror)
			)
		)
		(property "Manufacturer" "Bourns"
			(at 0 0 0)
			(unlocked yes)
			(layer "B.Fab")
			(hide yes)
			(effects
				(font
					(size 1 1)
					(thickness 0.15)
				)
				(justify mirror)
			)
		)
		(property "License" "Apache-2.0"
			(at 0 0 0)
			(unlocked yes)
			(layer "B.Fab")
			(hide yes)
			(effects
				(font
					(size 1 1)
					(thickness 0.15)
				)
				(justify mirror)
			)
		)
		(property "Author" "Antmicro"
			(at 0 0 0)
			(unlocked yes)
			(layer "B.Fab")
			(hide yes)
			(effects
				(font
					(size 1 1)
					(thickness 0.15)
				)
				(justify mirror)
			)
		)
		(property "Val" "0R"
			(at 0 0 0)
			(unlocked yes)
			(layer "B.Fab")
			(hide yes)
			(effects
				(font
					(size 1 1)
					(thickness 0.15)
				)
				(justify mirror)
			)
		)
		(property "Tolerance" "1%"
			(at 0 0 0)
			(unlocked yes)
			(layer "B.Fab")
			(hide yes)
			(effects
				(font
					(size 1 1)
					(thickness 0.15)
				)
				(justify mirror)
			)
		)
		(sheetname "/")
		(sheetfile "antmicro-m2-oculink-adapter-hw.kicad_sch")
		(attr smd dnp)
		(fp_rect
			(start -0.7 0.35)
			(end 0.7 -0.35)
			(stroke
				(width 0.05)
				(type default)
			)
			(fill no)
			(layer "B.CrtYd")
		)
		(fp_rect
			(start -0.3 0.15)
			(end 0.298 -0.148)
			(stroke
				(width 0.15)
				(type solid)
			)
			(fill no)
			(layer "B.Fab")
		)
		(fp_text user "License: Apache-2.0"
			(at -0.71 -4.25 0)
			(layer "B.Fab")
			(effects
				(font
					(size 0.7 0.7)
					(thickness 0.15)
				)
				(justify left bottom mirror)
			)
		)
		(fp_text user "Author: Antmicro"
			(at -0.71 -5.25 0)
			(layer "B.Fab")
			(effects
				(font
					(size 0.7 0.7)
					(thickness 0.15)
				)
				(justify left bottom mirror)
			)
		)
		(fp_text user "${REFERENCE}"
			(at -0.71 -3.25 0)
			(layer "B.Fab")
			(effects
				(font
					(size 0.7 0.7)
					(thickness 0.15)
				)
				(justify left bottom mirror)
			)
		)
		(pad "" smd roundrect
			(at -0.346 0 180)
			(size 0.318 0.36)
			(layers "B.Paste")
			(roundrect_rratio 0.25)
		)
		(pad "" smd roundrect
			(at 0.344 0 180)
			(size 0.318 0.36)
			(layers "B.Paste")
			(roundrect_rratio 0.25)
		)
		(pad "1" smd roundrect
			(at -0.32 0 180)
			(size 0.46 0.4)
			(layers "B.Cu" "B.Mask")
			(roundrect_rratio 0.25)
			(net 13 "/PCIe_{REF0}_R.CK+")
			(pintype "passive")
		)
		(pad "2" smd roundrect
			(at 0.32 0 180)
			(size 0.46 0.4)
			(layers "B.Cu" "B.Mask")
			(roundrect_rratio 0.25)
			(net 55 "/~{PERST}")
			(pintype "passive")
		)
	)
	(footprint "antmicro-footprints:R_0201"
		(layer "B.Cu")
		(at 146.64 94.38 90)
		(descr "Resistor SMD 0201")
		(tags "resistor SMD 0201")
		(property "Reference" "R5"
			(at -2.9 -0.05 90)
			(layer "B.SilkS")
			(effects
				(font
					(size 0.7 0.7)
					(thickness 0.15)
				)
				(justify right top mirror)
			)
		)
		(property "Value" "R_0R_0201"
			(at 0 -1.25 90)
			(layer "B.Fab")
			(effects
				(font
					(size 0.7 0.7)
					(thickness 0.15)
				)
				(justify right top mirror)
			)
		)
		(property "Datasheet" "https://www.bourns.com/docs/product-datasheets/cr.pdf"
			(at 0 0 90)
			(layer "B.Fab")
			(hide yes)
			(effects
				(font
					(size 1.27 1.27)
					(thickness 0.15)
				)
				(justify mirror)
			)
		)
		(property "Description" "SMD Chip Resistor"
			(at 0 0 90)
			(layer "B.Fab")
			(hide yes)
			(effects
				(font
					(size 1.27 1.27)
					(thickness 0.15)
				)
				(justify mirror)
			)
		)
		(property "MPN" "CR0201-FX-0R00GLF"
			(at 0 0 270)
			(unlocked yes)
			(layer "B.Fab")
			(hide yes)
			(effects
				(font
					(size 1 1)
					(thickness 0.15)
				)
				(justify mirror)
			)
		)
		(property "Manufacturer" "Bourns"
			(at 0 0 270)
			(unlocked yes)
			(layer "B.Fab")
			(hide yes)
			(effects
				(font
					(size 1 1)
					(thickness 0.15)
				)
				(justify mirror)
			)
		)
		(property "License" "Apache-2.0"
			(at 0 0 270)
			(unlocked yes)
			(layer "B.Fab")
			(hide yes)
			(effects
				(font
					(size 1 1)
					(thickness 0.15)
				)
				(justify mirror)
			)
		)
		(property "Author" "Antmicro"
			(at 0 0 270)
			(unlocked yes)
			(layer "B.Fab")
			(hide yes)
			(effects
				(font
					(size 1 1)
					(thickness 0.15)
				)
				(justify mirror)
			)
		)
		(property "Val" "0R"
			(at 0 0 270)
			(unlocked yes)
			(layer "B.Fab")
			(hide yes)
			(effects
				(font
					(size 1 1)
					(thickness 0.15)
				)
				(justify mirror)
			)
		)
		(property "Tolerance" "1%"
			(at 0 0 270)
			(unlocked yes)
			(layer "B.Fab")
			(hide yes)
			(effects
				(font
					(size 1 1)
					(thickness 0.15)
				)
				(justify mirror)
			)
		)
		(sheetname "/")
		(sheetfile "antmicro-m2-oculink-adapter-hw.kicad_sch")
		(attr smd dnp)
		(fp_rect
			(start -0.7 0.35)
			(end 0.7 -0.35)
			(stroke
				(width 0.05)
				(type default)
			)
			(fill no)
			(layer "B.CrtYd")
		)
		(fp_rect
			(start -0.3 0.15)
			(end 0.298 -0.148)
			(stroke
				(width 0.15)
				(type solid)
			)
			(fill no)
			(layer "B.Fab")
		)
		(fp_text user "License: Apache-2.0"
			(at -0.71 -4.25 90)
			(layer "B.Fab")
			(effects
				(font
					(size 0.7 0.7)
					(thickness 0.15)
				)
				(justify right top mirror)
			)
		)
		(fp_text user "${REFERENCE}"
			(at -0.71 -3.25 90)
			(layer "B.Fab")
			(effects
				(font
					(size 0.7 0.7)
					(thickness 0.15)
				)
				(justify right top mirror)
			)
		)
		(fp_text user "Author: Antmicro"
			(at -0.71 -5.25 90)
			(layer "B.Fab")
			(effects
				(font
					(size 0.7 0.7)
					(thickness 0.15)
				)
				(justify right top mirror)
			)
		)
		(pad "" smd roundrect
			(at -0.346 0 90)
			(size 0.318 0.36)
			(layers "B.Paste")
			(roundrect_rratio 0.25)
		)
		(pad "" smd roundrect
			(at 0.344 0 90)
			(size 0.318 0.36)
			(layers "B.Paste")
			(roundrect_rratio 0.25)
		)
		(pad "1" smd roundrect
			(at -0.32 0 90)
			(size 0.46 0.4)
			(layers "B.Cu" "B.Mask")
			(roundrect_rratio 0.25)
			(net 38 "/PCIe_{REF0}.CK-")
			(pintype "passive")
		)
		(pad "2" smd roundrect
			(at 0.32 0 90)
			(size 0.46 0.4)
			(layers "B.Cu" "B.Mask")
			(roundrect_rratio 0.25)
			(net 54 "/~{CPRSNT}")
			(pintype "passive")
		)
	)
)
